FILE_TYPE = CONNECTIVITY;
{Allegro Design Entry HDL 17.2-2016 S081 (4005846) 1/11/2022}
"PAGE_NUMBER" = 295;
0"NC";
1"P3V3_AUX\g";
2"P3V3_AUX\g";
3"P3V3_AUX\g";
4"P3V3_OCP_SFF_R\g";
5"P3V3_OCP_SFF\g";
6"P3V3_AUX\g";
7"P3V3_OCP_SFF_R\g";
8"P3V3_E1S_0\g";
9"P3V3_E1S_0_R\g";
10"P3V3_E1S_0_R\g";
11"P3V3_AUX\g";
12"GND\g";
13"GND\g";
14"GND\g";
15"GND\g";
16"GND\g";
17"GND\g";
18"GND\g";
19"GND\g";
20"NC_INA230_1_NC5";
21"OCP_SFF_P3V3_ADC_ALERT";
22"OCP_SFF_P3V3_ADC_ALERT_R";
23"NC_INA230_1_NC1";
24"NC_INA230_1_NC2";
25"NC_INA230_1_NC3";
26"NC_INA230_1_NC0";
27"NC_INA230_1_NC4";
28"INA230_1_A1";
29"INA230_1_A0";
30"SMB_INA230_1_3V3AUX_SCL_R1";
31"SMB_INA230_1_3V3AUX_SDA_R1";
32"VSENSE_P3V3_INA230_1_INP";
33"VSENSE_P3V3_INA230_1_INN";
34"NC_INA230_2_NC1";
35"E1S_0_P3V3_ADC_ALERT";
36"E1S_0_P3V3_ADC_ALERT_R";
37"NC_INA230_2_NC3";
38"NC_INA230_2_NC4";
39"NC_INA230_2_NC2";
40"NC_INA230_2_NC0";
41"NC_INA230_2_NC5";
42"VSENSE_P3V3_INA230_2_INN";
43"VSENSE_P3V3_INA230_2_INP";
44"SMB_INA230_2_3V3AUX_SDA_R1";
45"SMB_INA230_2_3V3AUX_SCL_R1";
46"INA230_2_A0";
47"INA230_2_A1";
48"SMB_INA230_1_3V3AUX_SDA_R";
49"SMB_INA230_1_3V3AUX_SCL_R";
50"SMB_INA230_2_3V3AUX_SCL_R";
51"SMB_INA230_2_3V3AUX_SDA_R";
%"Q_RES"
"1","(4350,725)","0","pure_quanta","I122";
;
PART_NUMBER"CS00002JB13"
PACK_TYPE"0402LF"
MATERIAL"CHIP"
VALUE"0"
$LOCATION"R3752"
CDS_LIB"pure_quanta"
TOLERANCE"5%"
WATTAGE"1/16W"
CDS_LOCATION"R3752"
$SEC"1"
CDS_SEC"1";
"B"
$PN"2"35;
"A"
$PN"1"36;
%"UNIVERSAL_POWER"
"1","(2425,1475)","0","logical_power","I123";
;
HDL_POWER"P3V3_AUX"
CDS_LIB"logical_power";
"A"3;
%"UNIVERSAL_GND"
"1","(2175,800)","0","logical_power","I124";
;
HDL_POWER"GND"
CDS_LIB"logical_power";
"A"16;
%"Q_CAP"
"1","(2175,1075)","0","pure_quanta","I125";
;
PART_NUMBER"CH4104K1B00"
VOLTAGE"25V"
PACK_TYPE"0402"
MATERIAL"X7R"
VALUE"0.1UF"
TOLERANCE"10%"
$LOCATION"C2067"
CDS_LIB"pure_quanta"
CDS_LOCATION"C2067"
$SEC"1"
CDS_SEC"1";
"B"
$PN"2"16;
"A"
$PN"1"3;
%"UNIVERSAL_GND"
"1","(3400,-175)","0","logical_power","I128";
;
CDS_LIB"logical_power"
HDL_POWER"GND";
"A"13;
%"INA230AIRGTR"
"1","(2875,475)","0","pure_quanta","I129";
;
PART_NUMBER"AL000230001"
PART_TYPE"SMLF"
MATERIAL"IC"
VALUE"INA230AIRGTR"
$LOCATION"U276"
CDS_LIB"pure_quanta"
CDS_LMAN_SYM_OUTLINE"-250,300,250,-300"
NEEDS_NO_SIZE"TRUE"
CDS_LOCATION"U276"
$SEC"1"
CDS_SEC"1";
"TH"
$PN"TH"13;
"GND"
$PN"10"13;
"NC5"
$PN"16"41;
"NC4"
$PN"15"38;
"NC3"
$PN"14"37;
"NC2"
$PN"8"39;
"NC1"
$PN"7"34;
"NC0"
$PN"6"40;
"ALERT"
$PN"3"36;
"IN-"
$PN"12"42;
"IN+"
$PN"13"43;
"BUS"
$PN"11"9;
"SDA"
$PN"4"44;
"SCL"
$PN"5"45;
"A0"
$PN"2"46;
"A1"
$PN"1"47;
"VS"
$PN"9"3;
%"Q_RES"
"1","(1275,475)","0","pure_quanta","I130";
;
PART_NUMBER"CS03322FB03"
MATERIAL"CHIP"
WATTAGE"1/16W"
PACK_TYPE"0402LF"
TOLERANCE"1%"
VALUE"33.2"
$LOCATION"R3754"
CDS_LIB"pure_quanta"
CDS_LOCATION"R3754"
$SEC"1"
CDS_SEC"1";
"B"
$PN"2"45;
"A"
$PN"1"50;
%"Q_RES"
"1","(1275,425)","0","pure_quanta","I131";
;
PART_NUMBER"CS03322FB03"
VALUE"33.2"
TOLERANCE"1%"
MATERIAL"CHIP"
$LOCATION"R3756"
CDS_LIB"pure_quanta"
PACK_TYPE"0402LF"
WATTAGE"1/16W"
CDS_LOCATION"R3756"
$SEC"1"
CDS_SEC"1";
"B"
$PN"2"44;
"A"
$PN"1"51;
%"Q_RES"
"1","(1300,-125)","0","pure_quanta","I132";
;
PART_NUMBER"CS01002FB07"
MATERIAL"CHIP"
VALUE"10"
TOLERANCE"1%"
PACK_TYPE"0402LF"
WATTAGE"1/16W"
$LOCATION"R3758"
CDS_LIB"pure_quanta"
CDS_LOCATION"R3758"
$SEC"1"
CDS_SEC"1";
"B"
$PN"2"43;
"A"
$PN"1"10;
%"Q_CAP"
"1","(1650,-275)","0","pure_quanta","I133";
;
PART_NUMBER"CH4104K1B00"
PACK_TYPE"0402"
VALUE"0.1UF"
MATERIAL"X7R"
TOLERANCE"10%"
VOLTAGE"25V"
$LOCATION"C2071"
CDS_LIB"pure_quanta"
CDS_LOCATION"C2071"
$SEC"1"
CDS_SEC"1";
"B"
$PN"2"42;
"A"
$PN"1"43;
%"Q_RES"
"1","(1300,-400)","0","pure_quanta","I134";
;
PART_NUMBER"CS01002FB07"
MATERIAL"CHIP"
WATTAGE"1/16W"
PACK_TYPE"0402LF"
TOLERANCE"1%"
VALUE"10"
$LOCATION"R3760"
CDS_LIB"pure_quanta"
CDS_LOCATION"R3760"
$SEC"1"
CDS_SEC"1";
"B"
$PN"2"42;
"A"
$PN"1"8;
%"Q_RES"
"1","(750,1000)","0","pure_quanta","I135";
;
PART_NUMBER"CS24702FB06"
VALUE"4.7K"
WATTAGE"1/16W"
MATERIAL"EMPTY"
PACK_TYPE"0402LF"
TOLERANCE"1%"
$LOCATION"R3764"
CDS_LIB"pure_quanta"
CDS_LOCATION"R3764"
$SEC"1"
CDS_SEC"1";
"B"
$PN"2"46;
"A"
$PN"1"15;
%"Q_RES"
"1","(750,1075)","0","pure_quanta","I136";
;
PART_NUMBER"CS24702FB06"
MATERIAL"CHIP"
TOLERANCE"1%"
WATTAGE"1/16W"
VALUE"4.7K"
PACK_TYPE"0402LF"
$LOCATION"R3763"
CDS_LIB"pure_quanta"
CDS_LOCATION"R3763"
$SEC"1"
CDS_SEC"1";
"B"
$PN"2"47;
"A"
$PN"1"15;
%"UNIVERSAL_GND"
"1","(175,875)","0","logical_power","I137";
;
HDL_POWER"GND"
CDS_LIB"logical_power";
"A"15;
%"UNIVERSAL_POWER"
"1","(-100,225)","0","logical_power","I140";
;
HDL_POWER"P3V3_E1S_0_R"
CDS_LIB"logical_power";
"A"10;
%"Q_CAP"
"1","(-500,650)","0","pure_quanta","I142";
;
PART_NUMBER"CH4104K1B00"
VALUE"0.1UF"
PACK_TYPE"0402"
TOLERANCE"10%"
VOLTAGE"25V"
MATERIAL"X7R"
$LOCATION"C2069"
CDS_LIB"pure_quanta"
CDS_LOCATION"C2069"
$SEC"1"
CDS_SEC"1";
"B"
$PN"2"14;
"A"
$PN"1"9;
%"UNIVERSAL_GND"
"1","(-500,375)","0","logical_power","I143";
;
CDS_LIB"logical_power"
HDL_POWER"GND";
"A"14;
%"UNIVERSAL_POWER"
"1","(-1175,225)","0","logical_power","I145";
;
HDL_POWER"P3V3_E1S_0"
CDS_LIB"logical_power";
"A"8;
%"Q_RES"
"2","(1550,825)","0","pure_quanta","I146";
;
PART_NUMBER"CS00002JB13"
PACK_TYPE"0402LF"
WATTAGE"1/16W"
TOLERANCE"5%"
MATERIAL"CHIP"
VALUE"0"
$LOCATION"R3751"
CDS_LIB"pure_quanta"
CDS_LOCATION"R3751"
$SEC"1"
CDS_SEC"1";
"A"
$PN"1"46;
"B"
$PN"2"44;
%"UNIVERSAL_POWER"
"1","(-250,975)","0","logical_power","I147";
;
HDL_POWER"P3V3_E1S_0_R"
CDS_LIB"logical_power";
"A"9;
%"UNIVERSAL_POWER"
"1","(4125,1375)","0","logical_power","I148";
;
HDL_POWER"P3V3_AUX"
CDS_LIB"logical_power";
"A"2;
%"Q_RES"
"2","(4125,1175)","0","pure_quanta","I149";
;
PART_NUMBER"CS24702FB06"
VALUE"4.7K"
TOLERANCE"1%"
WATTAGE"1/16W"
MATERIAL"CHIP"
PACK_TYPE"0402LF"
$LOCATION"R4093"
CDS_LIB"pure_quanta"
CDS_LOCATION"R4093"
$SEC"1"
CDS_SEC"1";
"A"
$PN"1"2;
"B"
$PN"2"36;
%"UNIVERSAL_POWER"
"1","(4150,3975)","0","logical_power","I150";
;
HDL_POWER"P3V3_AUX"
CDS_LIB"logical_power";
"A"1;
%"Q_RES"
"2","(4150,3775)","0","pure_quanta","I151";
;
PART_NUMBER"CS24702FB06"
VALUE"4.7K"
PACK_TYPE"0402LF"
TOLERANCE"1%"
WATTAGE"1/16W"
MATERIAL"CHIP"
$LOCATION"R4094"
CDS_LIB"pure_quanta"
CDS_LOCATION"R4094"
$SEC"1"
CDS_SEC"1";
"A"
$PN"1"1;
"B"
$PN"2"22;
%"Q_RES"
"1","(-600,2675)","0","pure_quanta","I152";
;
PART_NUMBER"CS+0108F128"
VALUE"0.01"
TOLERANCE"1%"
MATERIAL"CHIP"
WATTAGE"1W"
PACK_TYPE"2512LF"
LOCATION"R3645"
CDS_LIB"pure_quanta"
$SEC"1"
CDS_SEC"1";
"B"
$PN"2"7;
"A"
$PN"1"5;
%"Q_RES"
"1","(-600,75)","0","pure_quanta","I153";
;
PART_NUMBER"CS+0108F128"
PACK_TYPE"2512LF"
WATTAGE"1W"
VALUE"0.01"
TOLERANCE"1%"
MATERIAL"CHIP"
LOCATION"R3767"
CDS_LIB"pure_quanta"
$SEC"1"
CDS_SEC"1";
"B"
$PN"2"10;
"A"
$PN"1"8;
%"INA230AIRGTR"
"1","(2875,3075)","0","pure_quanta","I30";
;
PART_NUMBER"AL000230001"
PART_TYPE"SMLF"
MATERIAL"IC"
VALUE"INA230AIRGTR"
$LOCATION"U266"
CDS_LIB"pure_quanta"
CDS_LMAN_SYM_OUTLINE"-250,300,250,-300"
NEEDS_NO_SIZE"TRUE"
CDS_LOCATION"U266"
$SEC"1"
CDS_SEC"1";
"TH"
$PN"TH"12;
"GND"
$PN"10"12;
"NC5"
$PN"16"20;
"NC4"
$PN"15"27;
"NC3"
$PN"14"25;
"NC2"
$PN"8"24;
"NC1"
$PN"7"23;
"NC0"
$PN"6"26;
"ALERT"
$PN"3"22;
"IN-"
$PN"12"33;
"IN+"
$PN"13"32;
"BUS"
$PN"11"4;
"SDA"
$PN"4"31;
"SCL"
$PN"5"30;
"A0"
$PN"2"29;
"A1"
$PN"1"28;
"VS"
$PN"9"6;
%"Q_RES"
"1","(625,3350)","0","pure_quanta","I31";
;
PART_NUMBER"CS24702FB06"
WATTAGE"1/16W"
TOLERANCE"1%"
MATERIAL"CHIP"
PACK_TYPE"0402LF"
VALUE"4.7K"
$LOCATION"R3616"
CDS_LIB"pure_quanta"
CDS_LOCATION"R3616"
$SEC"1"
CDS_SEC"1";
"B"
$PN"2"28;
"A"
$PN"1"18;
%"UNIVERSAL_POWER"
"1","(2425,4075)","0","logical_power","I33";
;
HDL_POWER"P3V3_AUX"
CDS_LIB"logical_power";
"A"6;
%"Q_CAP"
"1","(2175,3675)","0","pure_quanta","I34";
;
PART_NUMBER"CH4104K1B00"
TOLERANCE"10%"
PACK_TYPE"0402"
VOLTAGE"25V"
MATERIAL"X7R"
VALUE"0.1UF"
$LOCATION"C2015"
CDS_LIB"pure_quanta"
CDS_LOCATION"C2015"
$SEC"1"
CDS_SEC"1";
"B"
$PN"2"19;
"A"
$PN"1"6;
%"Q_RES"
"1","(4350,3325)","0","pure_quanta","I35";
;
PART_NUMBER"CS00002JB13"
MATERIAL"CHIP"
VALUE"0"
PACK_TYPE"0402LF"
$LOCATION"R3563"
WATTAGE"1/16W"
TOLERANCE"5%"
CDS_LIB"pure_quanta"
CDS_LOCATION"R3563"
$SEC"1"
CDS_SEC"1";
"B"
$PN"2"21;
"A"
$PN"1"22;
%"UNIVERSAL_GND"
"1","(3400,2425)","0","logical_power","I36";
;
HDL_POWER"GND"
CDS_LIB"logical_power";
"A"12;
%"UNIVERSAL_GND"
"1","(2175,3400)","0","logical_power","I37";
;
CDS_LIB"logical_power"
HDL_POWER"GND";
"A"19;
%"Q_RES"
"1","(1275,3075)","0","pure_quanta","I38";
;
PART_NUMBER"CS03322FB03"
MATERIAL"CHIP"
TOLERANCE"1%"
VALUE"33.2"
PACK_TYPE"0402LF"
WATTAGE"1/16W"
$LOCATION"R3600"
CDS_LIB"pure_quanta"
CDS_LOCATION"R3600"
$SEC"1"
CDS_SEC"1";
"B"
$PN"2"30;
"A"
$PN"1"49;
%"Q_RES"
"1","(1275,3025)","0","pure_quanta","I39";
;
PART_NUMBER"CS03322FB03"
MATERIAL"CHIP"
TOLERANCE"1%"
VALUE"33.2"
$LOCATION"R3601"
WATTAGE"1/16W"
PACK_TYPE"0402LF"
CDS_LIB"pure_quanta"
CDS_LOCATION"R3601"
$SEC"1"
CDS_SEC"1";
"B"
$PN"2"31;
"A"
$PN"1"48;
%"Q_RES"
"1","(625,3275)","0","pure_quanta","I40";
;
PART_NUMBER"CS24702FB06"
WATTAGE"1/16W"
VALUE"4.7K"
TOLERANCE"1%"
MATERIAL"EMPTY"
PACK_TYPE"0402LF"
$LOCATION"R3617"
CDS_LIB"pure_quanta"
CDS_LOCATION"R3617"
$SEC"1"
CDS_SEC"1";
"B"
$PN"2"29;
"A"
$PN"1"18;
%"Q_RES"
"1","(1300,2475)","0","pure_quanta","I41";
;
PART_NUMBER"CS01002FB07"
PACK_TYPE"0402LF"
VALUE"10"
TOLERANCE"1%"
MATERIAL"CHIP"
WATTAGE"1/16W"
$LOCATION"R3602"
CDS_LIB"pure_quanta"
CDS_LOCATION"R3602"
$SEC"1"
CDS_SEC"1";
"B"
$PN"2"32;
"A"
$PN"1"7;
%"Q_RES"
"1","(1300,2200)","0","pure_quanta","I43";
;
PART_NUMBER"CS01002FB07"
MATERIAL"CHIP"
WATTAGE"1/16W"
PACK_TYPE"0402LF"
VALUE"10"
TOLERANCE"1%"
$LOCATION"R3603"
CDS_LIB"pure_quanta"
CDS_LOCATION"R3603"
$SEC"1"
CDS_SEC"1";
"B"
$PN"2"33;
"A"
$PN"1"5;
%"UNIVERSAL_GND"
"1","(200,3150)","0","logical_power","I45";
;
CDS_LIB"logical_power"
HDL_POWER"GND";
"A"18;
%"UNIVERSAL_GND"
"1","(-500,2975)","0","logical_power","I49";
;
HDL_POWER"GND"
CDS_LIB"logical_power";
"A"17;
%"Q_CAP"
"1","(-500,3250)","0","pure_quanta","I50";
;
PART_NUMBER"CH4104K1B00"
PACK_TYPE"0402"
VALUE"0.1UF"
VOLTAGE"25V"
TOLERANCE"10%"
MATERIAL"X7R"
$LOCATION"C2024"
CDS_LIB"pure_quanta"
CDS_LOCATION"C2024"
$SEC"1"
CDS_SEC"1";
"B"
$PN"2"17;
"A"
$PN"1"4;
%"Q_CAP"
"1","(1650,2325)","0","pure_quanta","I77";
;
PART_NUMBER"CH4104K1B00"
VALUE"0.1UF"
VOLTAGE"25V"
TOLERANCE"10%"
MATERIAL"X7R"
PACK_TYPE"0402"
$LOCATION"C2027"
CDS_LIB"pure_quanta"
CDS_LOCATION"C2027"
$SEC"1"
CDS_SEC"1";
"B"
$PN"2"33;
"A"
$PN"1"32;
%"UNIVERSAL_POWER"
"1","(-100,2825)","0","logical_power","I79";
;
HDL_POWER"P3V3_OCP_SFF_R"
CDS_LIB"logical_power";
"A"7;
%"UNIVERSAL_POWER"
"1","(-250,3575)","0","logical_power","I80";
;
HDL_POWER"P3V3_OCP_SFF_R"
CDS_LIB"logical_power";
"A"4;
%"UNIVERSAL_POWER"
"1","(-1175,2825)","0","logical_power","I81";
;
HDL_POWER"P3V3_OCP_SFF"
CDS_LIB"logical_power";
"A"5;
%"UNIVERSAL_POWER"
"1","(1825,4125)","0","logical_power","I87";
;
HDL_POWER"P3V3_AUX"
CDS_LIB"logical_power";
"A"11;
%"Q_RES"
"2","(1825,3700)","0","pure_quanta","I88";
;
PART_NUMBER"CS24702FB06"
VALUE"4.7K"
TOLERANCE"1%"
MATERIAL"EMPTY"
WATTAGE"1/16W"
PACK_TYPE"0402LF"
$LOCATION"R3628"
CDS_LIB"pure_quanta"
CDS_LOCATION"R3628"
$SEC"1"
CDS_SEC"1";
"A"
$PN"1"11;
"B"
$PN"2"28;
%"Q_RES"
"2","(1525,3700)","0","pure_quanta","I89";
;
PART_NUMBER"CS24702FB06"
VALUE"4.7K"
PACK_TYPE"0402LF"
MATERIAL"CHIP"
WATTAGE"1/16W"
TOLERANCE"1%"
$LOCATION"R3627"
CDS_LIB"pure_quanta"
CDS_LOCATION"R3627"
$SEC"1"
CDS_SEC"1";
"A"
$PN"1"11;
"B"
$PN"2"29;
END.
